FILE_TYPE = MULTI_PHYS_TABLE;
PART 'FET_N_DUAL'
{================================================================================================================================================================================}
:VALUE      | PACK_TYPE | MATERIAL | PART_NUMBER     = EnvComp | PART_NUMBER  | JEDEC_TYPE      | CLASS | DESCRIPTION          | HEIGHT     | COMPONENT_TYPE | LEAD_LENGTH | LPID  | SPEED_URL | Status |RPL| AML | Bus_Unit | Days ;
{================================================================================================================================================================================}
'2N7002DW'  | 'SMLF'    | 'FET'    | 'D24280-001'(!) = 'YES;YES;YES;UNK;ok;VLD' | 'D24280-001' | 'SSOP6_53_65MA' | 'IC'  | 'DUAL N CHANNEL FET' | '.044 IN'  | 'SMALLSMT'     | ''          | '374' | 'http://speed.intel.com:8081/speed/module/pdm/item/pdm_item_detail_direct.asp?item_cde=D24280-001&item_rev=01&url_param=unused' | 'Approved' | 'YES' | '5' | 'SMO_IC' | '84' 
'2N7002DW'  | 'SMLF'    | 'EMPTY'  | 'D24280-001'(!) = 'YES;YES;YES;UNK;ok;VLD' | 'D24280-001' | 'SSOP6_53_65MA' | 'IO'  | 'DUAL N CHANNEL FET' | '.044 IN'  | 'SMALLSMT'     | ''          | '374' | 'http://speed.intel.com:8081/speed/module/pdm/item/pdm_item_detail_direct.asp?item_cde=D24280-001&item_rev=01&url_param=unused' | 'Approved' | 'YES' | '5' | 'SMO_IC' | '84' 
'NTJD4001N' | 'SMLF'    | 'FET'    | 'E40049-001'(!) = 'YES;YES;YES;UNK;ok;VLD' | 'E40049-001' | 'SOT363A'       | 'IC'  | 'DUAL N CHANNEL FET' | '0.043 IN' | 'SMALLSMT'     | ''          | '723' | 'http://speed.intel.com:8081/speed/module/pdm/item/pdm_item_detail_direct.asp?item_cde=E40049-001&item_rev=01&url_param=unused' | 'Conditional' | 'YES' | '2' | 'SMO_IC' | '84' 
'NTJD4001N' | 'SMLF'    | 'EMPTY'  | 'E40049-001'(!) = 'YES;YES;YES;UNK;ok;VLD' | 'E40049-001' | 'SOT363A'       | 'IO'  | 'DUAL N CHANNEL FET' | '0.043 IN' | 'SMALLSMT'     | ''          | '723' | 'http://speed.intel.com:8081/speed/module/pdm/item/pdm_item_detail_direct.asp?item_cde=E40049-001&item_rev=01&url_param=unused' | 'Conditional' | 'YES' | '2' | 'SMO_IC' | '84' 
END_PART
END.
